(kicad_pcb
	(version 20260206)
	(generator "pcbnew")
	(generator_version "10.0")
	(general
		(thickness 1.6)
		(legacy_teardrops no)
	)
	(paper "A4")
	(title_block
		(title "Bryce Canyon_R.DPB_16317-1_OCP.brd")
		(comment 1 "Bryce Canyon / footprints 1433-1439 of 2099")
	)
	(layers
		(0 "F.Cu" signal "TOP")
		(4 "In1.Cu" signal "L2GND")
		(6 "In2.Cu" signal "L3")
		(8 "In3.Cu" signal "L4VCC")
		(10 "In4.Cu" signal "L5VCC")
		(12 "In5.Cu" signal "L6")
		(14 "In6.Cu" signal "L7GND")
		(2 "B.Cu" signal "BOTTOM")
		(9 "F.Adhes" user "F.Adhesive")
		(11 "B.Adhes" user "B.Adhesive")
		(13 "F.Paste" user "Package Geometry/Pastemask Top")
		(15 "B.Paste" user "Package Geometry/Pastemask Bottom")
		(5 "F.SilkS" user "Ref Des/Silkscreen Top")
		(7 "B.SilkS" user "Ref Des/Silkscreen Bottom")
		(1 "F.Mask" user "Board Geometry/Soldermask Top")
		(3 "B.Mask" user "Board Geometry/Soldermask Bottom")
		(17 "Dwgs.User" user "User.Drawings")
		(19 "Cmts.User" user "User.Comments")
		(21 "Eco1.User" user "User.Eco1")
		(23 "Eco2.User" user "User.Eco2")
		(25 "Edge.Cuts" user "Board Geometry/Outline")
		(27 "Margin" user)
		(31 "F.CrtYd" user "Package Geometry/Place Bound Top")
		(29 "B.CrtYd" user "Package Geometry/Place Bound Bottom")
		(35 "F.Fab" user "Ref Des/Assembly Top")
		(33 "B.Fab" user "Ref Des/Assembly Bottom")
	)
	(footprint ""
		(layer "F.Cu")
		(at 245.888002 -132.958078 -90)
		(property "Reference" "U23"
			(at 0 0 270)
			(layer "F.SilkS")
			(hide yes)
			(effects
				(font
					(size 1.27 1.27)
				)
			)
		)
		(property "Value" "PCA9511ADP-T-GP"
			(at 0 -13.1572 270)
			(unlocked yes)
			(layer "F.Fab")
			(hide yes)
			(effects
				(font
					(size 1.016 1.016)
					(thickness 0.1524)
				)
			)
		)
		(property "Device Type" "SSOIC8-2H44"
			(at 0 -15.1892 270)
			(unlocked yes)
			(layer "F.Fab")
			(hide yes)
			(effects
				(font
					(size 1.016 1.016)
					(thickness 0.1524)
				)
			)
		)
		(duplicate_pad_numbers_are_jumpers no)
		(fp_line
			(start -1.7018 1.0414)
			(end -1.7018 2.9718)
			(stroke
				(width 0.635)
				(type default)
			)
			(layer "F.SilkS")
		)
		(fp_line
			(start -1.9304 1.016)
			(end -1.9304 -1.016)
			(stroke
				(width 0.1524)
				(type default)
			)
			(layer "F.SilkS")
		)
		(fp_line
			(start 1.0922 1.016)
			(end -1.9304 1.016)
			(stroke
				(width 0.1524)
				(type default)
			)
			(layer "F.SilkS")
		)
		(fp_line
			(start -1.524 0)
			(end -1.9304 0.4064)
			(stroke
				(width 0.1524)
				(type default)
			)
			(layer "F.SilkS")
		)
		(fp_line
			(start -1.524 0)
			(end -1.9304 -0.4064)
			(stroke
				(width 0.1524)
				(type default)
			)
			(layer "F.SilkS")
		)
		(fp_line
			(start -1.9304 -1.016)
			(end 1.0922 -1.016)
			(stroke
				(width 0.1524)
				(type default)
			)
			(layer "F.SilkS")
		)
		(fp_line
			(start 1.0922 -1.016)
			(end 1.0922 1.016)
			(stroke
				(width 0.1524)
				(type default)
			)
			(layer "F.SilkS")
		)
		(fp_poly
			(pts
				(xy -1.1938 -1.016) (xy 1.0922 -1.016) (xy 1.0922 1.016) (xy -1.1938 1.016)
			)
			(stroke
				(width 0)
				(type default)
			)
			(fill yes)
			(layer "F.SilkS")
		)
		(fp_rect
			(start -2.0066 3.3401)
			(end 2.0066 -3.3401)
			(stroke
				(width 0)
				(type default)
			)
			(fill no)
			(layer "F.CrtYd")
		)
		(fp_poly
			(pts
				(xy -2.0066 -3.3401) (xy 2.0066 -3.3401) (xy 2.0066 3.3401) (xy -2.0066 3.3401)
			)
			(stroke
				(width 0)
				(type default)
			)
			(fill no)
			(layer "F.Fab")
		)
		(pad "1" smd rect
			(at -0.97536 2.0701 270)
			(size 0.4064 1.524)
			(layers "F.Cu" "F.Mask" "F.Paste")
			(net "I2C_DPB_BUFF_EN")
		)
		(pad "2" smd rect
			(at -0.32512 2.0701 270)
			(size 0.4064 1.524)
			(layers "F.Cu" "F.Mask" "F.Paste")
			(net "I2C_DPB_B_SCL_BUF")
		)
		(pad "3" smd rect
			(at 0.32512 2.0701 270)
			(size 0.4064 1.524)
			(layers "F.Cu" "F.Mask" "F.Paste")
			(net "I2C_DPB_B_SCL")
		)
		(pad "4" smd rect
			(at 0.97536 2.0701 270)
			(size 0.4064 1.524)
			(layers "F.Cu" "F.Mask" "F.Paste")
			(net "GND")
		)
		(pad "5" smd rect
			(at 0.97536 -2.0701 270)
			(size 0.4064 1.524)
			(layers "F.Cu" "F.Mask" "F.Paste")
			(net "I2C_DPB_BUFF_READY")
		)
		(pad "6" smd rect
			(at 0.32512 -2.0701 270)
			(size 0.4064 1.524)
			(layers "F.Cu" "F.Mask" "F.Paste")
			(net "I2C_DPB_B_SDA")
		)
		(pad "7" smd rect
			(at -0.32512 -2.0701 270)
			(size 0.4064 1.524)
			(layers "F.Cu" "F.Mask" "F.Paste")
			(net "I2C_DPB_B_SDA_BUF")
		)
		(pad "8" smd rect
			(at -0.97536 -2.0701 270)
			(size 0.4064 1.524)
			(layers "F.Cu" "F.Mask" "F.Paste")
			(net "P3V3_STBY_B")
		)
	)
	(footprint ""
		(layer "F.Cu")
		(at 355.139752 -248.750074 -90)
		(property "Reference" "VIA16"
			(at 0 0 270)
			(layer "F.SilkS")
			(hide yes)
			(effects
				(font
					(size 1.27 1.27)
				)
			)
		)
		(property "Value" "100OHM-8L-2D36MM-L16-GP"
			(at -3.4036 -0.4572 270)
			(unlocked yes)
			(layer "F.Fab")
			(hide yes)
			(effects
				(font
					(size 1.016 1.016)
					(thickness 0.1524)
				)
			)
		)
		(property "Device Type" "VIA-PCIE-4P-427097"
			(at -3.4036 -1.9812 270)
			(unlocked yes)
			(layer "F.Fab")
			(hide yes)
			(effects
				(font
					(size 1.016 1.016)
					(thickness 0.1524)
				)
			)
		)
		(duplicate_pad_numbers_are_jumpers no)
		(fp_rect
			(start -2.1336 0.4826)
			(end 2.1336 -0.4826)
			(stroke
				(width 0)
				(type default)
			)
			(fill no)
			(layer "F.CrtYd")
		)
		(fp_rect
			(start -2.1336 0.4826)
			(end 2.1336 -0.4826)
			(stroke
				(width 0)
				(type default)
			)
			(fill no)
			(layer "F.Fab")
		)
		(pad "1" thru_hole circle
			(at -1.651 0 270)
			(size 0.508 0.508)
			(drill 0.254)
			(layers "*.Cu" "*.Mask")
			(remove_unused_layers no)
			(net "GND")
			(clearance 0.2286)
			(thermal_gap 0.2286)
		)
		(pad "2" thru_hole circle
			(at -0.635 0 270)
			(size 0.508 0.508)
			(drill 0.254)
			(layers "*.Cu" "*.Mask")
			(remove_unused_layers no)
			(net "PHY_DRV_B_TO_SCC_B_7_DP")
			(clearance 0.2286)
			(thermal_gap 0.2286)
		)
		(pad "3" thru_hole circle
			(at 0.635 0 270)
			(size 0.508 0.508)
			(drill 0.254)
			(layers "*.Cu" "*.Mask")
			(remove_unused_layers no)
			(net "PHY_DRV_B_TO_SCC_B_7_DN")
			(clearance 0.2286)
			(thermal_gap 0.2286)
		)
		(pad "4" thru_hole circle
			(at 1.651 0 270)
			(size 0.508 0.508)
			(drill 0.254)
			(layers "*.Cu" "*.Mask")
			(remove_unused_layers no)
			(net "GND")
			(clearance 0.2286)
			(thermal_gap 0.2286)
		)
	)
	(footprint ""
		(layer "F.Cu")
		(at 393.674854 -63.799974)
		(property "Reference" ""
			(at 0 0 0)
			(layer "F.SilkS")
			(hide yes)
			(effects
				(font
					(size 1.27 1.27)
				)
			)
		)
		(property "Value" "*"
			(at -8.398764 -8.057642 0)
			(unlocked yes)
			(layer "F.Fab")
			(hide yes)
			(effects
				(font
					(size 1.016 1.016)
					(thickness 0.1524)
				)
			)
		)
		(duplicate_pad_numbers_are_jumpers no)
		(fp_poly
			(pts
				(arc
					(start 7.3152 0)
					(mid 0 7.3152)
					(end -7.3152 0)
				)
				(arc
					(start -7.3152 -5.9944)
					(mid 0 -13.3096)
					(end 7.3152 -5.9944)
				)
			)
			(stroke
				(width 0)
				(type default)
			)
			(fill no)
			(layer "B.CrtYd")
		)
		(fp_poly
			(pts
				(arc
					(start 7.3152 0)
					(mid 0 7.3152)
					(end -7.3152 0)
				)
				(arc
					(start -7.3152 -5.9944)
					(mid 0 -13.3096)
					(end 7.3152 -5.9944)
				)
			)
			(stroke
				(width 0)
				(type default)
			)
			(fill no)
			(layer "F.CrtYd")
		)
		(fp_poly
			(pts
				(arc
					(start 7.3152 0)
					(mid 0 7.3152)
					(end -7.3152 0)
				)
				(arc
					(start -7.3152 -5.9944)
					(mid 0 -13.3096)
					(end 7.3152 -5.9944)
				)
			)
			(stroke
				(width 0)
				(type default)
			)
			(fill no)
			(layer "B.Fab")
		)
		(fp_poly
			(pts
				(arc
					(start 7.3152 0)
					(mid 0 7.3152)
					(end -7.3152 0)
				)
				(arc
					(start -7.3152 -5.9944)
					(mid 0 -13.3096)
					(end 7.3152 -5.9944)
				)
			)
			(stroke
				(width 0)
				(type default)
			)
			(fill no)
			(layer "F.Fab")
		)
		(pad "1" thru_hole oval
			(at 0 0)
			(size 14.0208 20.0152)
			(drill 0.0254
				(offset 0 -2.9972)
			)
			(layers "*.Cu" "*.Mask")
			(remove_unused_layers no)
			(net "Net_51")
			(clearance -1.002284)
			(thermal_gap 0.1524)
			(padstack
				(mode front_inner_back)
				(layer "Inner"
					(shape custom)
					(size 2.928012 2.928012)
					(options
						(anchor circle)
					)
					(primitives
						(gr_poly
							(pts
								(arc
									(start 4.571746 -2.084324)
									(mid 0.000333 7.430372)
									(end -4.571492 -2.084324)
								)
								(arc
									(start -4.571492 -2.084324)
									(mid -3.570296 -3.611977)
									(end -2.875026 -5.30098)
								)
								(arc
									(start -2.875026 -5.30098)
									(mid 0.000217 -7.43089)
									(end 2.87528 -5.30098)
								)
								(arc
									(start 2.87528 -5.30098)
									(mid 3.570511 -3.611956)
									(end 4.571746 -2.084324)
								)
							)
							(width 0)
							(fill yes)
						)
					)
					(clearance 0.1524)
				)
				(layer "B.Cu"
					(shape oval)
					(size 14.0208 20.0152)
					(offset 0 -2.9972)
					(clearance -1.002284)
				)
			)
		)
		(zone
			(layers "F.Cu" "B.Cu" "In1.Cu" "In2.Cu" "In3.Cu" "In4.Cu" "In5.Cu" "In6.Cu")
			(hatch none 0.5)
			(connect_pads
				(clearance 0)
			)
			(min_thickness 0.25)
			(keepout
				(tracks not_allowed)
				(vias allowed)
				(pads allowed)
				(copperpour not_allowed)
				(footprints allowed)
			)
			(placement
				(enabled no)
				(sheetname "")
			)
			(fill
				(thermal_gap 0.5)
				(thermal_bridge_width 0.5)
				(island_removal_mode 0)
			)
			(polygon
				(pts
					(arc
						(start 386.664454 -69.794374)
						(mid 393.674854 -76.804774)
						(end 400.685254 -69.794374)
					)
					(arc
						(start 400.685254 -63.799974)
						(mid 393.674854 -56.789574)
						(end 386.664454 -63.799974)
					)
				)
			)
		)
	)
	(footprint ""
		(layer "F.Cu")
		(at 398.907 -246.761 180)
		(property "Reference" "R299"
			(at 0 0 180)
			(layer "F.SilkS")
			(hide yes)
			(effects
				(font
					(size 1.27 1.27)
				)
			)
		)
		(property "Value" "0R2J-2-GP"
			(at 0.064008 -3.993896 180)
			(unlocked yes)
			(layer "F.Fab")
			(hide yes)
			(effects
				(font
					(size 1.016 1.016)
					(thickness 0.1524)
				)
			)
		)
		(property "Device Type" "R402H16"
			(at 0.064008 -5.517896 180)
			(unlocked yes)
			(layer "F.Fab")
			(hide yes)
			(effects
				(font
					(size 1.016 1.016)
					(thickness 0.1524)
				)
			)
		)
		(duplicate_pad_numbers_are_jumpers no)
		(fp_line
			(start 0.508 -0.9398)
			(end -0.508 -0.9398)
			(stroke
				(width 0.1524)
				(type default)
			)
			(layer "F.SilkS")
		)
		(fp_line
			(start -0.508 -0.9398)
			(end -0.508 0.9398)
			(stroke
				(width 0.1524)
				(type default)
			)
			(layer "F.SilkS")
		)
		(fp_rect
			(start -0.508 0.9398)
			(end 0.508 -0.9398)
			(stroke
				(width 0)
				(type default)
			)
			(fill no)
			(layer "F.CrtYd")
		)
		(fp_rect
			(start -0.508 0.9398)
			(end 0.508 -0.9398)
			(stroke
				(width 0)
				(type default)
			)
			(fill no)
			(layer "F.Fab")
		)
		(pad "1" smd custom
			(at 0 -0.4445 180)
			(size 0.1397 0.1397)
			(layers "F.Cu" "F.Mask" "F.Paste")
			(net "SW_HDD_G8")
			(options
				(clearance outline)
				(anchor circle)
			)
			(primitives
				(gr_poly
					(pts
						(arc
							(start -0.1778 -0.2794)
							(mid -0.249642 -0.249642)
							(end -0.2794 -0.1778)
						)
						(arc
							(start -0.2794 0.1778)
							(mid -0.249642 0.249642)
							(end -0.1778 0.2794)
						)
						(arc
							(start 0.1778 0.2794)
							(mid 0.249642 0.249642)
							(end 0.2794 0.1778)
						)
						(arc
							(start 0.2794 -0.1778)
							(mid 0.249642 -0.249642)
							(end 0.1778 -0.2794)
						)
					)
					(width 0)
					(fill yes)
				)
			)
		)
		(pad "2" smd custom
			(at 0 0.4445 180)
			(size 0.1397 0.1397)
			(layers "F.Cu" "F.Mask" "F.Paste")
			(net "SW_HDD_R8")
			(options
				(clearance outline)
				(anchor circle)
			)
			(primitives
				(gr_poly
					(pts
						(arc
							(start -0.1778 -0.2794)
							(mid -0.249642 -0.249642)
							(end -0.2794 -0.1778)
						)
						(arc
							(start -0.2794 0.1778)
							(mid -0.249642 0.249642)
							(end -0.1778 0.2794)
						)
						(arc
							(start 0.1778 0.2794)
							(mid 0.249642 0.249642)
							(end 0.2794 0.1778)
						)
						(arc
							(start 0.2794 -0.1778)
							(mid 0.249642 -0.249642)
							(end 0.1778 -0.2794)
						)
					)
					(width 0)
					(fill yes)
				)
			)
		)
	)
	(footprint ""
		(layer "F.Cu")
		(at 172.847 -99.314)
		(property "Reference" "R412"
			(at 0 0 0)
			(layer "F.SilkS")
			(hide yes)
			(effects
				(font
					(size 1.27 1.27)
				)
			)
		)
		(property "Value" "130R3F-GP"
			(at -0.0254 -2.5146 0)
			(unlocked yes)
			(layer "F.Fab")
			(hide yes)
			(effects
				(font
					(size 1.016 1.016)
					(thickness 0.1524)
				)
			)
		)
		(property "Device Type" "R603H22"
			(at -0.0254 -4.0386 0)
			(unlocked yes)
			(layer "F.Fab")
			(hide yes)
			(effects
				(font
					(size 1.016 1.016)
					(thickness 0.1524)
				)
			)
		)
		(duplicate_pad_numbers_are_jumpers no)
		(fp_line
			(start -0.4826 0)
			(end -0.2032 0)
			(stroke
				(width 0.2032)
				(type default)
			)
			(layer "F.SilkS")
		)
		(fp_line
			(start 0.2032 0)
			(end 0.4826 0)
			(stroke
				(width 0.2032)
				(type default)
			)
			(layer "F.SilkS")
		)
		(fp_rect
			(start -0.5842 1.3335)
			(end 0.5842 -1.3335)
			(stroke
				(width 0)
				(type default)
			)
			(fill no)
			(layer "F.CrtYd")
		)
		(fp_rect
			(start -0.5842 1.3335)
			(end 0.5842 -1.3335)
			(stroke
				(width 0)
				(type default)
			)
			(fill no)
			(layer "F.Fab")
		)
		(pad "1" smd custom
			(at 0 -0.762)
			(size 0.2159 0.2159)
			(layers "F.Cu" "F.Mask" "F.Paste")
			(net "P5V_B_2")
			(options
				(clearance outline)
				(anchor circle)
			)
			(primitives
				(gr_poly
					(pts
						(arc
							(start -0.3302 -0.4318)
							(mid -0.402042 -0.402042)
							(end -0.4318 -0.3302)
						)
						(arc
							(start -0.4318 0.3302)
							(mid -0.402042 0.402042)
							(end -0.3302 0.4318)
						)
						(arc
							(start 0.3302 0.4318)
							(mid 0.402042 0.402042)
							(end 0.4318 0.3302)
						)
						(arc
							(start 0.4318 -0.3302)
							(mid 0.402042 -0.402042)
							(end 0.3302 -0.4318)
						)
					)
					(width 0)
					(fill yes)
				)
			)
		)
		(pad "2" smd custom
			(at 0 0.762)
			(size 0.2159 0.2159)
			(layers "F.Cu" "F.Mask" "F.Paste")
			(net "FLT_HDD17")
			(options
				(clearance outline)
				(anchor circle)
			)
			(primitives
				(gr_poly
					(pts
						(arc
							(start -0.3302 -0.4318)
							(mid -0.402042 -0.402042)
							(end -0.4318 -0.3302)
						)
						(arc
							(start -0.4318 0.3302)
							(mid -0.402042 0.402042)
							(end -0.3302 0.4318)
						)
						(arc
							(start 0.3302 0.4318)
							(mid 0.402042 0.402042)
							(end 0.4318 0.3302)
						)
						(arc
							(start 0.4318 -0.3302)
							(mid 0.402042 -0.402042)
							(end 0.3302 -0.4318)
						)
					)
					(width 0)
					(fill yes)
				)
			)
		)
	)
	(footprint ""
		(layer "F.Cu")
		(at 455.93 -267.843 180)
		(property "Reference" "C160"
			(at 0 0 180)
			(layer "F.SilkS")
			(hide yes)
			(effects
				(font
					(size 1.27 1.27)
				)
			)
		)
		(property "Value" "SC1U16V3KX-5GP"
			(at 0 -2.8194 180)
			(unlocked yes)
			(layer "F.Fab")
			(hide yes)
			(effects
				(font
					(size 1.016 1.016)
					(thickness 0.1524)
				)
			)
		)
		(property "Device Type" "C603H36"
			(at 0 -4.3434 180)
			(unlocked yes)
			(layer "F.Fab")
			(hide yes)
			(effects
				(font
					(size 1.016 1.016)
					(thickness 0.1524)
				)
			)
		)
		(duplicate_pad_numbers_are_jumpers no)
		(fp_line
			(start 0.508 0)
			(end -0.508 0)
			(stroke
				(width 0.2032)
				(type default)
			)
			(layer "F.SilkS")
		)
		(fp_rect
			(start -0.5842 1.3335)
			(end 0.5842 -1.3335)
			(stroke
				(width 0)
				(type default)
			)
			(fill no)
			(layer "F.CrtYd")
		)
		(fp_rect
			(start -0.5842 1.3335)
			(end 0.5842 -1.3335)
			(stroke
				(width 0)
				(type default)
			)
			(fill no)
			(layer "F.Fab")
		)
		(pad "1" smd custom
			(at 0 -0.762 180)
			(size 0.2159 0.2159)
			(layers "F.Cu" "F.Mask" "F.Paste")
			(net "P5V_HDD10")
			(options
				(clearance outline)
				(anchor circle)
			)
			(primitives
				(gr_poly
					(pts
						(arc
							(start -0.3302 -0.4318)
							(mid -0.402042 -0.402042)
							(end -0.4318 -0.3302)
						)
						(arc
							(start -0.4318 0.3302)
							(mid -0.402042 0.402042)
							(end -0.3302 0.4318)
						)
						(arc
							(start 0.3302 0.4318)
							(mid 0.402042 0.402042)
							(end 0.4318 0.3302)
						)
						(arc
							(start 0.4318 -0.3302)
							(mid 0.402042 -0.402042)
							(end 0.3302 -0.4318)
						)
					)
					(width 0)
					(fill yes)
				)
			)
		)
		(pad "2" smd custom
			(at 0 0.762 180)
			(size 0.2159 0.2159)
			(layers "F.Cu" "F.Mask" "F.Paste")
			(net "GND")
			(options
				(clearance outline)
				(anchor circle)
			)
			(primitives
				(gr_poly
					(pts
						(arc
							(start -0.3302 -0.4318)
							(mid -0.402042 -0.402042)
							(end -0.4318 -0.3302)
						)
						(arc
							(start -0.4318 0.3302)
							(mid -0.402042 0.402042)
							(end -0.3302 0.4318)
						)
						(arc
							(start 0.3302 0.4318)
							(mid 0.402042 0.402042)
							(end 0.4318 0.3302)
						)
						(arc
							(start 0.4318 -0.3302)
							(mid 0.402042 -0.402042)
							(end 0.3302 -0.4318)
						)
					)
					(width 0)
					(fill yes)
				)
			)
		)
	)
	(footprint ""
		(layer "F.Cu")
		(at 102.616 -357.632 -90)
		(property "Reference" "C549"
			(at 0 0 270)
			(layer "F.SilkS")
			(hide yes)
			(effects
				(font
					(size 1.27 1.27)
				)
			)
		)
		(property "Value" "SCD1U25V2KX-2-GP"
			(at 1.1811 -2.7051 270)
			(unlocked yes)
			(layer "F.Fab")
			(hide yes)
			(effects
				(font
					(size 1.016 1.016)
					(thickness 0.1524)
				)
			)
		)
		(property "Device Type" "C402H22"
			(at 1.1811 -4.2291 270)
			(unlocked yes)
			(layer "F.Fab")
			(hide yes)
			(effects
				(font
					(size 1.016 1.016)
					(thickness 0.1524)
				)
			)
		)
		(duplicate_pad_numbers_are_jumpers no)
		(fp_rect
			(start -0.4318 0.9525)
			(end 0.4318 -0.9525)
			(stroke
				(width 0)
				(type default)
			)
			(fill no)
			(layer "F.CrtYd")
		)
		(fp_rect
			(start -0.4318 0.9525)
			(end 0.4318 -0.9525)
			(stroke
				(width 0)
				(type default)
			)
			(fill no)
			(layer "F.Fab")
		)
		(pad "1" smd custom
			(at 0 -0.4445 270)
			(size 0.1524 0.1524)
			(layers "F.Cu" "F.Mask" "F.Paste")
			(net "P12V_CLIP")
			(options
				(clearance outline)
				(anchor circle)
			)
			(primitives
				(gr_poly
					(pts
						(arc
							(start 0.3048 -0.2032)
							(mid 0.275042 -0.275042)
							(end 0.2032 -0.3048)
						)
						(arc
							(start -0.2032 -0.3048)
							(mid -0.275042 -0.275042)
							(end -0.3048 -0.2032)
						)
						(arc
							(start -0.3048 0.2032)
							(mid -0.275042 0.275042)
							(end -0.2032 0.3048)
						)
						(arc
							(start 0.2032 0.3048)
							(mid 0.275042 0.275042)
							(end 0.3048 0.2032)
						)
					)
					(width 0)
					(fill yes)
				)
			)
		)
		(pad "2" smd custom
			(at 0 0.4445 270)
			(size 0.1524 0.1524)
			(layers "F.Cu" "F.Mask" "F.Paste")
			(net "GND")
			(options
				(clearance outline)
				(anchor circle)
			)
			(primitives
				(gr_poly
					(pts
						(arc
							(start 0.3048 -0.2032)
							(mid 0.275042 -0.275042)
							(end 0.2032 -0.3048)
						)
						(arc
							(start -0.2032 -0.3048)
							(mid -0.275042 -0.275042)
							(end -0.3048 -0.2032)
						)
						(arc
							(start -0.3048 0.2032)
							(mid -0.275042 0.275042)
							(end -0.2032 0.3048)
						)
						(arc
							(start 0.2032 0.3048)
							(mid 0.275042 0.275042)
							(end 0.3048 0.2032)
						)
					)
					(width 0)
					(fill yes)
				)
			)
		)
	)
)
